(kicad_pcb
	(version 20260206)
	(generator "pcbnew")
	(generator_version "10.0")
	(general
		(thickness 1.6)
		(legacy_teardrops no)
	)
	(paper "A4")
	(title_block
		(title "04192023_DAF0TMB3IC0_F0TG_MB_C_brd_V02_OCP.brd")
		(comment 1 "Grand Teton / footprint 2929 of 8354 (J38), pads 110-175 of 175")
	)
	(layers
		(0 "F.Cu" signal "TOP")
		(4 "In1.Cu" signal "GND")
		(6 "In2.Cu" signal "IN1")
		(8 "In3.Cu" signal "GND1")
		(10 "In4.Cu" signal "IN2")
		(12 "In5.Cu" signal "GND2")
		(14 "In6.Cu" signal "IN3")
		(16 "In7.Cu" signal "GND3")
		(18 "In8.Cu" signal "VCC")
		(20 "In9.Cu" signal "VCC1")
		(22 "In10.Cu" signal "GND4")
		(24 "In11.Cu" signal "IN4")
		(26 "In12.Cu" signal "GND5")
		(28 "In13.Cu" signal "IN5")
		(30 "In14.Cu" signal "GND6")
		(32 "In15.Cu" signal "IN6")
		(34 "In16.Cu" signal "GND7")
		(2 "B.Cu" signal "BOTTOM")
		(9 "F.Adhes" user "F.Adhesive")
		(11 "B.Adhes" user "B.Adhesive")
		(13 "F.Paste" user "Package Geometry/Pastemask Top")
		(15 "B.Paste" user "Package Geometry/Pastemask Bottom")
		(5 "F.SilkS" user "Ref Des/Silkscreen Top")
		(7 "B.SilkS" user "Ref Des/Silkscreen Bottom")
		(1 "F.Mask" user "Board Geometry/Soldermask Top")
		(3 "B.Mask" user "Board Geometry/Soldermask Bottom")
		(17 "Dwgs.User" user "User.Drawings")
		(19 "Cmts.User" user "User.Comments")
		(21 "Eco1.User" user "User.Eco1")
		(23 "Eco2.User" user "User.Eco2")
		(25 "Edge.Cuts" user "Board Geometry/Outline")
		(27 "Margin" user)
		(31 "F.CrtYd" user "Package Geometry/Place Bound Top")
		(29 "B.CrtYd" user "Package Geometry/Place Bound Bottom")
		(35 "F.Fab" user "Ref Des/Assembly Top")
		(33 "B.Fab" user "Ref Des/Assembly Bottom")
	)
	(footprint ""
		(layer "F.Cu")
		(at 421.901874 -5.569966 -90)
		(property "Reference" "J38"
			(at -8.103616 -20.50034 0)
			(unlocked yes)
			(layer "F.SilkS")
			(effects
				(font
					(size 0.7874 0.5842)
					(thickness 0.1524)
				)
				(justify left)
			)
		)
		(property "Value" ""
			(at 0 0 270)
			(layer "F.Fab")
			(effects
				(font
					(size 1.27 1.27)
				)
			)
		)
		(duplicate_pad_numbers_are_jumpers no)
		(pad "B38" smd rect
			(at -5.700014 7.14502 180)
			(size 0.381 1.4478)
			(layers "F.Cu" "F.Mask" "F.Paste")
			(net "GND")
		)
		(pad "B39" smd rect
			(at -5.700014 7.744968 180)
			(size 0.381 1.4478)
			(layers "F.Cu" "F.Mask" "F.Paste")
			(net "P5E_CPU0_G3_TX_C_DP<7>")
		)
		(pad "B40" smd rect
			(at -5.700014 8.344916 180)
			(size 0.381 1.4478)
			(layers "F.Cu" "F.Mask" "F.Paste")
			(net "P5E_CPU0_G3_TX_C_DN<7>")
		)
		(pad "B41" smd rect
			(at -5.700014 8.945118 180)
			(size 0.381 1.4478)
			(layers "F.Cu" "F.Mask" "F.Paste")
			(net "GND")
		)
		(pad "B42" smd rect
			(at -5.700014 9.545066 180)
			(size 0.381 1.4478)
			(layers "F.Cu" "F.Mask" "F.Paste")
			(net "OCP_SFF_PRSNT0_R_N")
		)
		(pad "B43" smd rect
			(at -5.700014 14.454886 180)
			(size 0.381 1.4478)
			(layers "F.Cu" "F.Mask" "F.Paste")
			(net "GND")
		)
		(pad "B44" smd rect
			(at -5.700014 15.055088 180)
			(size 0.381 1.4478)
			(layers "F.Cu" "F.Mask" "F.Paste")
			(net "P5E_CPU0_G3_TX_C_DP<8>")
		)
		(pad "B45" smd rect
			(at -5.700014 15.655036 180)
			(size 0.381 1.4478)
			(layers "F.Cu" "F.Mask" "F.Paste")
			(net "P5E_CPU0_G3_TX_C_DN<8>")
		)
		(pad "B46" smd rect
			(at -5.700014 16.254984 180)
			(size 0.381 1.4478)
			(layers "F.Cu" "F.Mask" "F.Paste")
			(net "GND")
		)
		(pad "B47" smd rect
			(at -5.700014 16.854932 180)
			(size 0.381 1.4478)
			(layers "F.Cu" "F.Mask" "F.Paste")
			(net "P5E_CPU0_G3_TX_C_DP<9>")
		)
		(pad "B48" smd rect
			(at -5.700014 17.45488 180)
			(size 0.381 1.4478)
			(layers "F.Cu" "F.Mask" "F.Paste")
			(net "P5E_CPU0_G3_TX_C_DN<9>")
		)
		(pad "B49" smd rect
			(at -5.700014 18.055082 180)
			(size 0.381 1.4478)
			(layers "F.Cu" "F.Mask" "F.Paste")
			(net "GND")
		)
		(pad "B50" smd rect
			(at -5.700014 18.65503 180)
			(size 0.381 1.4478)
			(layers "F.Cu" "F.Mask" "F.Paste")
			(net "P5E_CPU0_G3_TX_C_DP<10>")
		)
		(pad "B51" smd rect
			(at -5.700014 19.254978 180)
			(size 0.381 1.4478)
			(layers "F.Cu" "F.Mask" "F.Paste")
			(net "P5E_CPU0_G3_TX_C_DN<10>")
		)
		(pad "B52" smd rect
			(at -5.700014 19.854926 180)
			(size 0.381 1.4478)
			(layers "F.Cu" "F.Mask" "F.Paste")
			(net "GND")
		)
		(pad "B53" smd rect
			(at -5.700014 20.455128 180)
			(size 0.381 1.4478)
			(layers "F.Cu" "F.Mask" "F.Paste")
			(net "P5E_CPU0_G3_TX_C_DP<11>")
		)
		(pad "B54" smd rect
			(at -5.700014 21.055076 180)
			(size 0.381 1.4478)
			(layers "F.Cu" "F.Mask" "F.Paste")
			(net "P5E_CPU0_G3_TX_C_DN<11>")
		)
		(pad "B55" smd rect
			(at -5.700014 21.655024 180)
			(size 0.381 1.4478)
			(layers "F.Cu" "F.Mask" "F.Paste")
			(net "GND")
		)
		(pad "B56" smd rect
			(at -5.700014 22.254972 180)
			(size 0.381 1.4478)
			(layers "F.Cu" "F.Mask" "F.Paste")
			(net "P5E_CPU0_G3_TX_C_DP<12>")
		)
		(pad "B57" smd rect
			(at -5.700014 22.85492 180)
			(size 0.381 1.4478)
			(layers "F.Cu" "F.Mask" "F.Paste")
			(net "P5E_CPU0_G3_TX_C_DN<12>")
		)
		(pad "B58" smd rect
			(at -5.700014 23.455122 180)
			(size 0.381 1.4478)
			(layers "F.Cu" "F.Mask" "F.Paste")
			(net "GND")
		)
		(pad "B59" smd rect
			(at -5.700014 24.05507 180)
			(size 0.381 1.4478)
			(layers "F.Cu" "F.Mask" "F.Paste")
			(net "P5E_CPU0_G3_TX_C_DP<13>")
		)
		(pad "B60" smd rect
			(at -5.700014 24.655018 180)
			(size 0.381 1.4478)
			(layers "F.Cu" "F.Mask" "F.Paste")
			(net "P5E_CPU0_G3_TX_C_DN<13>")
		)
		(pad "B61" smd rect
			(at -5.700014 25.254966 180)
			(size 0.381 1.4478)
			(layers "F.Cu" "F.Mask" "F.Paste")
			(net "GND")
		)
		(pad "B62" smd rect
			(at -5.700014 25.854914 180)
			(size 0.381 1.4478)
			(layers "F.Cu" "F.Mask" "F.Paste")
			(net "P5E_CPU0_G3_TX_C_DP<14>")
		)
		(pad "B63" smd rect
			(at -5.700014 26.455116 180)
			(size 0.381 1.4478)
			(layers "F.Cu" "F.Mask" "F.Paste")
			(net "P5E_CPU0_G3_TX_C_DN<14>")
		)
		(pad "B64" smd rect
			(at -5.700014 27.055064 180)
			(size 0.381 1.4478)
			(layers "F.Cu" "F.Mask" "F.Paste")
			(net "GND")
		)
		(pad "B65" smd rect
			(at -5.700014 27.655012 180)
			(size 0.381 1.4478)
			(layers "F.Cu" "F.Mask" "F.Paste")
			(net "P5E_CPU0_G3_TX_C_DP<15>")
		)
		(pad "B66" smd rect
			(at -5.700014 28.25496 180)
			(size 0.381 1.4478)
			(layers "F.Cu" "F.Mask" "F.Paste")
			(net "P5E_CPU0_G3_TX_C_DN<15>")
		)
		(pad "B67" smd rect
			(at -5.700014 28.854908 180)
			(size 0.381 1.4478)
			(layers "F.Cu" "F.Mask" "F.Paste")
			(net "GND")
		)
		(pad "B68" smd rect
			(at -5.700014 29.45511 180)
			(size 0.381 1.4478)
			(layers "F.Cu" "F.Mask" "F.Paste")
			(net "TP_OCP_SFF_B68")
		)
		(pad "B69" smd rect
			(at -5.700014 30.055058 180)
			(size 0.381 1.4478)
			(layers "F.Cu" "F.Mask" "F.Paste")
			(net "TP_OCP_SFF_B69")
		)
		(pad "B70" smd rect
			(at -5.700014 30.655006 180)
			(size 0.381 1.4478)
			(layers "F.Cu" "F.Mask" "F.Paste")
			(net "OCP_SFF_PRSNT3_R_N")
		)
		(pad "G1" thru_hole circle
			(at 2.400046 -32.759904 180)
			(size 1.6256 1.6256)
			(drill 1.1176)
			(layers "*.Cu" "*.Mask")
			(remove_unused_layers no)
			(net "GND")
			(clearance 0)
		)
		(pad "G2" thru_hole circle
			(at 2.400046 -20.379944 180)
			(size 1.6256 1.6256)
			(drill 1.1176)
			(layers "*.Cu" "*.Mask")
			(remove_unused_layers no)
			(net "GND")
			(clearance 0)
		)
		(pad "G3" thru_hole circle
			(at 2.400046 0 180)
			(size 1.6256 1.6256)
			(drill 1.1176)
			(layers "*.Cu" "*.Mask")
			(remove_unused_layers no)
			(net "GND")
			(clearance 0)
		)
		(pad "G4" thru_hole circle
			(at 2.400046 12.5349 180)
			(size 1.6256 1.6256)
			(drill 1.1176)
			(layers "*.Cu" "*.Mask")
			(remove_unused_layers no)
			(net "GND")
			(clearance 0)
		)
		(pad "G5" thru_hole circle
			(at 2.400046 32.759904 180)
			(size 1.6256 1.6256)
			(drill 1.1176)
			(layers "*.Cu" "*.Mask")
			(remove_unused_layers no)
			(net "GND")
			(clearance 0)
		)
		(pad "OA1" smd rect
			(at -2.750058 -30.660086 180)
			(size 0.381 1.4478)
			(layers "F.Cu" "F.Mask" "F.Paste")
			(net "RST_PERST2_OCP_SFF_N")
		)
		(pad "OA2" smd rect
			(at -2.750058 -30.059884 180)
			(size 0.381 1.4478)
			(layers "F.Cu" "F.Mask" "F.Paste")
			(net "RST_PERST3_OCP_SFF_N")
		)
		(pad "OA3" smd rect
			(at -2.750058 -29.459936 180)
			(size 0.381 1.4478)
			(layers "F.Cu" "F.Mask" "F.Paste")
			(net "IRQ_LVC3_OCP_SFF_WAKE_N")
		)
		(pad "OA4" smd rect
			(at -2.750058 -28.859988 180)
			(size 0.381 1.4478)
			(layers "F.Cu" "F.Mask" "F.Paste")
			(net "OCP_SFF_ISO1_RBT_ARB_IN")
		)
		(pad "OA5" smd rect
			(at -2.750058 -28.26004 180)
			(size 0.381 1.4478)
			(layers "F.Cu" "F.Mask" "F.Paste")
			(net "OCP_SFF_ISO2_RBT_ARB_OUT")
		)
		(pad "OA6" smd rect
			(at -2.750058 -27.660092 180)
			(size 0.381 1.4478)
			(layers "F.Cu" "F.Mask" "F.Paste")
			(net "OCP_SFF_ID1")
		)
		(pad "OA7" smd rect
			(at -2.750058 -27.05989 180)
			(size 0.381 1.4478)
			(layers "F.Cu" "F.Mask" "F.Paste")
			(net "NCSI_OCP_SFF_TX_EN")
		)
		(pad "OA8" smd rect
			(at -2.750058 -26.459942 180)
			(size 0.381 1.4478)
			(layers "F.Cu" "F.Mask" "F.Paste")
			(net "NCSI_OCP_SFF_TXD1")
		)
		(pad "OA9" smd rect
			(at -2.750058 -25.859994 180)
			(size 0.381 1.4478)
			(layers "F.Cu" "F.Mask" "F.Paste")
			(net "NCSI_OCP_SFF_TXD0")
		)
		(pad "OA10" smd rect
			(at -2.750058 -25.260046 180)
			(size 0.381 1.4478)
			(layers "F.Cu" "F.Mask" "F.Paste")
			(net "GND")
		)
		(pad "OA11" smd rect
			(at -2.750058 -24.660098 180)
			(size 0.381 1.4478)
			(layers "F.Cu" "F.Mask" "F.Paste")
			(net "CLK_100M_CPU0_CLK05_DN")
		)
		(pad "OA12" smd rect
			(at -2.750058 -24.059896 180)
			(size 0.381 1.4478)
			(layers "F.Cu" "F.Mask" "F.Paste")
			(net "CLK_100M_CPU0_CLK05_DP")
		)
		(pad "OA13" smd rect
			(at -2.750058 -23.459948 180)
			(size 0.381 1.4478)
			(layers "F.Cu" "F.Mask" "F.Paste")
			(net "GND")
		)
		(pad "OA14" smd rect
			(at -2.750058 -22.86 180)
			(size 0.381 1.4478)
			(layers "F.Cu" "F.Mask" "F.Paste")
			(net "CLK_50M_NCSI_OCP_SFF_ISO")
		)
		(pad "OB1" smd rect
			(at -5.700014 -30.660086 180)
			(size 0.381 1.4478)
			(layers "F.Cu" "F.Mask" "F.Paste")
			(net "FM_OCP_SFF_PWR_GOOD")
		)
		(pad "OB2" smd rect
			(at -5.700014 -30.059884 180)
			(size 0.381 1.4478)
			(layers "F.Cu" "F.Mask" "F.Paste")
			(net "OCP_SFF_MAIN_PWR_EN_R")
		)
		(pad "OB3" smd rect
			(at -5.700014 -29.459936 180)
			(size 0.381 1.4478)
			(layers "F.Cu" "F.Mask" "F.Paste")
			(net "SGPIO_OCP_SFF_LD_N")
		)
		(pad "OB4" smd rect
			(at -5.700014 -28.859988 180)
			(size 0.381 1.4478)
			(layers "F.Cu" "F.Mask" "F.Paste")
			(net "SGPIO_OCP_SFF_DATAIN")
		)
		(pad "OB5" smd rect
			(at -5.700014 -28.26004 180)
			(size 0.381 1.4478)
			(layers "F.Cu" "F.Mask" "F.Paste")
			(net "SGPIO_OCP_SFF_DATAOUT")
		)
		(pad "OB6" smd rect
			(at -5.700014 -27.660092 180)
			(size 0.381 1.4478)
			(layers "F.Cu" "F.Mask" "F.Paste")
			(net "SGPIO_OCP_SFF_CLK")
		)
		(pad "OB7" smd rect
			(at -5.700014 -27.05989 180)
			(size 0.381 1.4478)
			(layers "F.Cu" "F.Mask" "F.Paste")
			(net "OCP_SFF_ID0")
		)
		(pad "OB8" smd rect
			(at -5.700014 -26.459942 180)
			(size 0.381 1.4478)
			(layers "F.Cu" "F.Mask" "F.Paste")
			(net "NCSI_OCP_SFF_RXD1")
		)
		(pad "OB9" smd rect
			(at -5.700014 -25.859994 180)
			(size 0.381 1.4478)
			(layers "F.Cu" "F.Mask" "F.Paste")
			(net "NCSI_OCP_SFF_RXD0")
		)
		(pad "OB10" smd rect
			(at -5.700014 -25.260046 180)
			(size 0.381 1.4478)
			(layers "F.Cu" "F.Mask" "F.Paste")
			(net "GND")
		)
		(pad "OB11" smd rect
			(at -5.700014 -24.660098 180)
			(size 0.381 1.4478)
			(layers "F.Cu" "F.Mask" "F.Paste")
			(net "CLK_100M_CPU0_CLK04_DN")
		)
		(pad "OB12" smd rect
			(at -5.700014 -24.059896 180)
			(size 0.381 1.4478)
			(layers "F.Cu" "F.Mask" "F.Paste")
			(net "CLK_100M_CPU0_CLK04_DP")
		)
		(pad "OB13" smd rect
			(at -5.700014 -23.459948 180)
			(size 0.381 1.4478)
			(layers "F.Cu" "F.Mask" "F.Paste")
			(net "GND")
		)
		(pad "OB14" smd rect
			(at -5.700014 -22.86 180)
			(size 0.381 1.4478)
			(layers "F.Cu" "F.Mask" "F.Paste")
			(net "NCSI_OCP_SFF_CRS_DV")
		)
	)
)
